# T6G (Grand Teton) — schematic parts with pin connectivity, parts 8232–8232 of 8303; source: Cadence DE-HDL packaged netlist (pstxprt.dat, pstxnet.dat, pstchip.dat)

U6015  PT5161LRS  IC  pkg BGA354_8-9X22-8  page 329
  A1  NCF_GND1  POWER  = NCF_A1_CPU1_P1_GND
  A35  NCF_GND2  POWER  = NCF_CPU1_P1_GND
  AA10  B_PETN1  OUT  = P5E_CPU1_P1_TX_BUF_DN<14>
  AA29  A_PETN1  OUT  = P5E_CPU1_P1_RX_DN<14>
  AB1  A_PERP1  IN  = P5E_CPU1_P1_RX_BUF_DP<14>
  AB35  B_PERN1  IN  = P5E_CPU1_P1_TX_C_DN<14>
  AC4  GND4  POWER  = GND
  AC13  GND1  POWER  = GND
  AC17  PWR_2A_1  POWER  = P0V9_CPU1_RT1_2A
  AC20  PWR_2A_2  POWER  = P0V9_CPU1_RT1_2A
  AC22  GND2  POWER  = GND
  AC32  GND3  POWER  = GND
  AD2  GND5  POWER  = GND
  AD34  GND6  POWER  = GND
  AE1  GND7  POWER  = GND
  AE35  GND8  POWER  = GND
  AF7  B_PETP2  OUT  = P5E_CPU1_P1_TX_BUF_DP<13>
  AF26  A_PETP2  OUT  = P5E_CPU1_P1_RX_DP<13>
  AG2  A_PERN2  IN  = P5E_CPU1_P1_RX_BUF_DN<13>
  AG34  B_PERP2  IN  = P5E_CPU1_P1_TX_C_DN<13>
  AH10  B_PETN2  OUT  = P5E_CPU1_P1_TX_BUF_DN<13>
  AH29  A_PETN2  OUT  = P5E_CPU1_P1_RX_DN<13>
  AJ1  A_PERP2  IN  = P5E_CPU1_P1_RX_BUF_DP<13>
  AJ35  B_PERN2  IN  = P5E_CPU1_P1_TX_C_DP<13>
  AK4  GND12  POWER  = GND
  AK13  GND9  POWER  = GND
  AK17  PWR_2A_3  POWER  = P0V9_CPU1_RT1_2A
  AK20  PWR_2A_4  POWER  = P0V9_CPU1_RT1_2A
  AK22  GND10  POWER  = GND
  AK32  GND11  POWER  = GND
  AL2  GND13  POWER  = GND
  AL34  GND14  POWER  = GND
  AM1  GND15  POWER  = GND
  AM35  GND16  POWER  = GND
  AN7  B_PETP3  OUT  = P5E_CPU1_P1_TX_BUF_DP<12>
  AN26  A_PETP3  OUT  = P5E_CPU1_P1_RX_DP<12>
  AP2  A_PERN3  IN  = P5E_CPU1_P1_RX_BUF_DN<12>
  AP34  B_PERP3  IN  = P5E_CPU1_P1_TX_C_DN<12>
  AR10  B_PETN3  OUT  = P5E_CPU1_P1_TX_BUF_DN<12>
  AR29  A_PETN3  OUT  = P5E_CPU1_P1_RX_DN<12>
  AT1  A_PERP3  IN  = P5E_CPU1_P1_RX_BUF_DP<12>
  AT35  B_PERN3  IN  = P5E_CPU1_P1_TX_C_DP<12>
  AU4  GND20  POWER  = GND
  AU13  GND17  POWER  = GND
  AU17  PWR_2A_5  POWER  = P0V9_CPU1_RT1_2A
  AU20  PWR_2A_6  POWER  = P0V9_CPU1_RT1_2A
  AU22  GND18  POWER  = GND
  AU32  GND19  POWER  = GND
  AV2  GND21  POWER  = GND
  AV34  GND22  POWER  = GND
  AW1  GND23  POWER  = GND
  AW35  GND24  POWER  = GND
  AY7  B_PETP4  OUT  = P5E_CPU1_P1_TX_BUF_DP<11>
  AY26  A_PETP4  OUT  = P5E_CPU1_P1_RX_DP<11>
  B3  JTAG_TCK  IN  = JTAG_TCK_RT_CPU1_P1
  B6  JTAG_TDI  IN  = JTAG_TDI_RT_CPU1_P1
  B9  JTAG_TDO  OUT  = JTAG_TDO_RT_CPU1_P1
  B12  JTAG_TMS  IN  = JTAG_TMS_RT_CPU1_P1
  B16  REFCLK_OUTP  OUT  = NC
  B19  GND25  POWER  = GND
  B23  SMB_ADDR2  IN  = RT_CPU1_P1_ADDR2
  B25  SMB_ADDR3  IN  = RT_CPU1_P1_ADDR3
  B28  SMBDAT  BI  = SMB_RT_CPU1_P1_R2_SDA
  B31  SMBCLK  BI  = SMB_RT_CPU1_P1_R2_SCL
  BA2  A_PERN4  IN  = P5E_CPU1_P1_RX_BUF_DN<11>
  BA34  B_PERP4  IN  = P5E_CPU1_P1_TX_C_DN<11>
  BB10  B_PETN4  OUT  = P5E_CPU1_P1_TX_BUF_DN<11>
  BB29  A_PETN4  OUT  = P5E_CPU1_P1_RX_DN<11>
  BC1  A_PERP4  IN  = P5E_CPU1_P1_RX_BUF_DP<11>
  BC35  B_PERN4  IN  = P5E_CPU1_P1_TX_C_DP<11>
  BD4  GND29  POWER  = GND
  BD13  GND26  POWER  = GND
  BD17  PWR_2A_7  POWER  = P0V9_CPU1_RT1_2A_2D
  BD20  PWR_2A_8  POWER  = P0V9_CPU1_RT1_2A_2D
  BD22  GND27  POWER  = GND
  BD32  GND28  POWER  = GND
  BE2  GND30  POWER  = GND
  BE34  GND31  POWER  = GND
  BF1  GND32  POWER  = GND
  BF35  GND33  POWER  = GND
  BG7  B_PETP5  OUT  = P5E_CPU1_P1_TX_BUF_DP<10>
  BG26  A_PETP5  OUT  = P5E_CPU1_P1_RX_DP<10>
  BH2  A_PERN5  IN  = P5E_CPU1_P1_RX_BUF_DN<10>
  BH34  B_PERP5  IN  = P5E_CPU1_P1_TX_C_DN<10>
  BJ10  B_PETN5  OUT  = P5E_CPU1_P1_TX_BUF_DN<10>
  BJ29  A_PETN5  OUT  = P5E_CPU1_P1_RX_DN<10>
  BK1  A_PERP5  IN  = P5E_CPU1_P1_RX_BUF_DP<10>
  BK35  B_PERN5  IN  = P5E_CPU1_P1_TX_C_DP<10>
  BL4  GND37  POWER  = GND
  BL13  GND34  POWER  = GND
  BL17  PWR_2D_1  POWER  = P0V9_CPU1_RT_2D
  BL20  PWR_2D_2  POWER  = P0V9_CPU1_RT_2D
  BL22  GND35  POWER  = GND
  BL32  GND36  POWER  = GND
  BM2  GND38  POWER  = GND
  BM34  GND39  POWER  = GND
  BN1  GND40  POWER  = GND
  BN35  GND41  POWER  = GND
  BP7  B_PETP6  OUT  = P5E_CPU1_P1_TX_BUF_DP<9>
  BP26  A_PETP6  OUT  = P5E_CPU1_P1_RX_DP<9>
  BR2  A_PERN6  IN  = P5E_CPU1_P1_RX_BUF_DN<9>
  BR34  B_PERP6  IN  = P5E_CPU1_P1_TX_C_DN<9>
  BT10  B_PETN6  OUT  = P5E_CPU1_P1_TX_BUF_DN<9>
  BT29  A_PETN6  OUT  = P5E_CPU1_P1_RX_DN<9>
  BU1  A_PERP6  IN  = P5E_CPU1_P1_RX_BUF_DP<9>
  BU35  B_PERN6  IN  = P5E_CPU1_P1_TX_C_DP<9>
  BV4  GND45  POWER  = GND
  BV13  GND42  POWER  = GND
  BV17  PWR_1D  POWER  = P1V8_CPU1_RT1_1A_1D
  BV20  PWR_1A_1  POWER  = P1V8_CPU1_RT1_1A
  BV22  GND43  POWER  = GND
  BV32  GND44  POWER  = GND
  BW2  GND46  POWER  = GND
  BW34  GND47  POWER  = GND
  BY1  GND48  POWER  = GND
  BY35  GND49  POWER  = GND
  C2  NCF_GND3  POWER  = NCF_CPU1_P1_GND
  C34  NCF_GND4  POWER  = NCF_CPU1_P1_GND
  CA7  B_PETP7  OUT  = P5E_CPU1_P1_TX_BUF_DP<8>
  CA26  A_PETP7  OUT  = P5E_CPU1_P1_RX_DP<8>
  CB2  A_PERN7  IN  = P5E_CPU1_P1_RX_BUF_DN<8>
  CB34  B_PERP7  IN  = P5E_CPU1_P1_TX_C_DN<8>
  CC10  B_PETN7  OUT  = P5E_CPU1_P1_TX_BUF_DN<8>
  CC29  A_PETN7  OUT  = P5E_CPU1_P1_RX_DN<8>
  CD1  A_PERP7  IN  = P5E_CPU1_P1_RX_BUF_DP<8>
  CD35  B_PERN7  IN  = P5E_CPU1_P1_TX_C_DP<8>
  CE4  GND53  POWER  = GND
  CE13  GND50  POWER  = GND
  CE17  PWR_1A_2  POWER  = P1V8_CPU1_RT1_1A
  CE20  PWR_1A_3  POWER  = P1V8_CPU1_RT1_1A
  CE22  GND51  POWER  = GND
  CE32  GND52  POWER  = GND
  CF2  GND54  POWER  = GND
  CF34  GND55  POWER  = GND
  CG1  GND56  POWER  = GND
  CG35  GND57  POWER  = GND
  CH7  B_PETP8  OUT  = P5E_CPU1_P1_TX_BUF_DP<7>
  CH26  A_PETP8  OUT  = P5E_CPU1_P1_RX_DP<7>
  CJ2  A_PERN8  IN  = P5E_CPU1_P1_RX_BUF_DN<7>
  CJ34  B_PERP8  IN  = P5E_CPU1_P1_TX_C_DN<7>
  CK10  B_PETN8  OUT  = P5E_CPU1_P1_TX_BUF_DN<7>
  CK29  A_PETN8  OUT  = P5E_CPU1_P1_RX_DN<7>
  CL1  A_PERP8  IN  = P5E_CPU1_P1_RX_BUF_DP<7>
  CL35  B_PERN8  IN  = P5E_CPU1_P1_TX_C_DP<7>
  CM4  GND61  POWER  = GND
  CM13  GND58  POWER  = GND
  CM17  PWR_1A_4  POWER  = P1V8_CPU1_RT1_1A
  CM20  PWR_1A_5  POWER  = P1V8_CPU1_RT1_1A
  CM22  GND59  POWER  = GND
  CM32  GND60  POWER  = GND
  CN2  GND62  POWER  = GND
  CN34  GND63  POWER  = GND
  CP1  GND64  POWER  = GND
  CP35  GND65  POWER  = GND
  CR7  B_PETP9  OUT  = P5E_CPU1_P1_TX_BUF_DP<6>
  CR26  A_PETP9  OUT  = P5E_CPU1_P1_RX_DP<6>
  CT2  A_PERN9  IN  = P5E_CPU1_P1_RX_BUF_DN<6>
  CT34  B_PERP9  IN  = P5E_CPU1_P1_TX_C_DN<6>
  CU10  B_PETN9  OUT  = P5E_CPU1_P1_TX_BUF_DN<6>
  CU29  A_PETN9  OUT  = P5E_CPU1_P1_RX_DN<6>
  CV1  A_PERP9  IN  = P5E_CPU1_P1_RX_BUF_DP<6>
  CV35  B_PERN9  IN  = P5E_CPU1_P1_TX_C_DP<6>
  CW4  GND69  POWER  = GND
  CW13  GND66  POWER  = GND
  CW17  PWR_2D_3  POWER  = P0V9_CPU1_RT_2D
  CW20  PWR_2D_4  POWER  = P0V9_CPU1_RT_2D
  CW22  GND67  POWER  = GND
  CW32  GND68  POWER  = GND
  CY2  GND70  POWER  = GND
  CY34  GND71  POWER  = GND
  D1  NCF_GND5  POWER  = NCF_CPU1_P1_GND
  D35  NCF_GND6  POWER  = NCF_CPU1_P1_GND
  DA1  GND72  POWER  = GND
  DA35  GND73  POWER  = GND
  DB7  B_PETP10  OUT  = P5E_CPU1_P1_TX_BUF_DP<5>
  DB26  A_PETP10  OUT  = P5E_CPU1_P1_RX_DP<5>
  DC2  A_PERN10  IN  = P5E_CPU1_P1_RX_BUF_DN<5>
  DC34  B_PERP10  IN  = P5E_CPU1_P1_TX_C_DN<5>
  DD10  B_PETN10  OUT  = P5E_CPU1_P1_TX_BUF_DN<5>
  DD29  A_PETN10  OUT  = P5E_CPU1_P1_RX_DN<5>
  DE1  A_PERP10  IN  = P5E_CPU1_P1_RX_BUF_DP<5>
  DE35  B_PERN10  IN  = P5E_CPU1_P1_TX_C_DP<5>
  DF4  GND77  POWER  = GND
  DF13  GND74  POWER  = GND
  DF17  PWR_2A_9  POWER  = P0V9_CPU1_RT1_2A_2D
  DF20  PWR_2A_10  POWER  = P0V9_CPU1_RT1_2A_2D
  DF22  GND75  POWER  = GND
  DF32  GND76  POWER  = GND
  DG2  GND78  POWER  = GND
  DG34  GND79  POWER  = GND
  DH1  GND80  POWER  = GND
  DH35  GND81  POWER  = GND
  DJ7  B_PETP11  OUT  = P5E_CPU1_P1_TX_BUF_DP<4>
  DJ26  A_PETP11  OUT  = P5E_CPU1_P1_RX_DP<4>
  DK2  A_PERN11  IN  = P5E_CPU1_P1_RX_BUF_DN<4>
  DK34  B_PERP11  IN  = P5E_CPU1_P1_TX_C_DN<4>
  DL10  B_PETN11  OUT  = P5E_CPU1_P1_TX_BUF_DN<4>
  DL29  A_PETN11  OUT  = P5E_CPU1_P1_RX_DN<4>
  DM1  A_PERP11  IN  = P5E_CPU1_P1_RX_BUF_DP<4>
  DM35  B_PERN11  IN  = P5E_CPU1_P1_TX_C_DP<4>
  DN4  GND85  POWER  = GND
  DN13  GND82  POWER  = GND
  DN17  PWR_2A_11  POWER  = P0V9_CPU1_RT1_2A
  DN20  PWR_2A_12  POWER  = P0V9_CPU1_RT1_2A
  DN22  GND83  POWER  = GND
  DN32  GND84  POWER  = GND
  DP2  GND86  POWER  = GND
  DP34  GND87  POWER  = GND
  DR1  GND88  POWER  = GND
  DR35  GND89  POWER  = GND
  DT7  B_PETP12  OUT  = P5E_CPU1_P1_TX_BUF_DP<3>
  DT26  A_PETP12  OUT  = P5E_CPU1_P1_RX_DP<3>
  DU2  A_PERN12  IN  = P5E_CPU1_P1_RX_BUF_DN<3>
  DU34  B_PERP12  IN  = P5E_CPU1_P1_TX_C_DN<3>
  DV10  B_PETN12  OUT  = P5E_CPU1_P1_TX_BUF_DN<3>
  DV29  A_PETN12  OUT  = P5E_CPU1_P1_RX_DN<3>
  DW1  A_PERP12  IN  = P5E_CPU1_P1_RX_BUF_DP<3>
  DW35  B_PERN12  IN  = P5E_CPU1_P1_TX_C_DP<3>
  DY4  GND93  POWER  = GND
  DY13  GND90  POWER  = GND
  DY17  PWR_2A_13  POWER  = P0V9_CPU1_RT1_2A
  DY20  PWR_2A_14  POWER  = P0V9_CPU1_RT1_2A
  DY22  GND91  POWER  = GND
  DY32  GND92  POWER  = GND
  E8  JTAG_TRST_N  IN  = JTAG_TRST_RT_CPU1_P1_N
  E11  RXDET_BYP  IN  = RXDET_BYP_RT_CPU1_P1
  E14  GND94  POWER  = GND
  E18  REFCLK_OUTN  OUT  = NC
  E27  GND95  POWER  = GND
  E30  T_SENSE  OUT  = GND
  E33  GND96  POWER  = GND
  EA2  GND97  POWER  = GND
  EA34  GND98  POWER  = GND
  EB1  GND99  POWER  = GND
  EB35  GND100  POWER  = GND
  EC7  B_PETP13  OUT  = P5E_CPU1_P1_TX_BUF_DP<2>
  EC26  A_PETP13  OUT  = P5E_CPU1_P1_RX_DP<2>
  ED2  A_PERN13  IN  = P5E_CPU1_P1_RX_BUF_DN<2>
  ED34  B_PERP13  IN  = P5E_CPU1_P1_TX_C_DN<2>
  EE10  B_PETN13  OUT  = P5E_CPU1_P1_TX_BUF_DN<2>
  EE29  A_PETN13  OUT  = P5E_CPU1_P1_RX_DN<2>
  EF1  A_PERP13  IN  = P5E_CPU1_P1_RX_BUF_DP<2>
  EF35  B_PERN13  IN  = P5E_CPU1_P1_TX_C_DP<2>
  EG4  GND104  POWER  = GND
  EG13  GND101  POWER  = GND
  EG17  PWR_2A_15  POWER  = P0V9_CPU1_RT1_2A
  EG20  PWR_2A_16  POWER  = P0V9_CPU1_RT1_2A
  EG22  GND102  POWER  = GND
  EG32  GND103  POWER  = GND
  EH2  GND105  POWER  = GND
  EH34  GND106  POWER  = GND
  EJ1  GND107  POWER  = GND
  EJ35  GND108  POWER  = GND
  EK7  B_PETP14  OUT  = P5E_CPU1_P1_TX_BUF_DP<1>
  EK26  A_PETP14  OUT  = P5E_CPU1_P1_RX_DP<1>
  EL2  A_PERN14  IN  = P5E_CPU1_P1_RX_BUF_DN<1>
  EL34  B_PERP14  IN  = P5E_CPU1_P1_TX_C_DP<1>
  EM10  B_PETN14  OUT  = P5E_CPU1_P1_TX_BUF_DN<1>
  EM29  A_PETN14  OUT  = P5E_CPU1_P1_RX_DN<1>
  EN1  A_PERP14  IN  = P5E_CPU1_P1_RX_BUF_DP<1>
  EN35  B_PERN14  IN  = P5E_CPU1_P1_TX_C_DN<1>
  EP4  GND112  POWER  = GND
  EP13  GND109  POWER  = GND
  EP17  PWR_2A_17  POWER  = P0V9_CPU1_RT1_2A
  EP20  PWR_2A_18  POWER  = P0V9_CPU1_RT1_2A
  EP22  GND110  POWER  = GND
  EP32  GND111  POWER  = GND
  ER2  GND113  POWER  = GND
  ER34  GND114  POWER  = GND
  ET1  GND115  POWER  = GND
  ET35  GND116  POWER  = GND
  EU7  B_PETP15  OUT  = P5E_CPU1_P1_TX_BUF_DP<0>
  EU26  A_PETP15  OUT  = P5E_CPU1_P1_RX_DP<0>
  EV2  A_PERN15  IN  = P5E_CPU1_P1_RX_BUF_DN<0>
  EV34  B_PERP15  IN  = P5E_CPU1_P1_TX_C_DN<0>
  EW10  B_PETN15  OUT  = P5E_CPU1_P1_TX_BUF_DN<0>
  EW29  A_PETN15  OUT  = P5E_CPU1_P1_RX_DN<0>
  EY1  A_PERP15  IN  = P5E_CPU1_P1_RX_BUF_DP<0>
  EY35  B_PERN15  IN  = P5E_CPU1_P1_TX_C_DP<0>
  F2  PERST_N  IN  = RST_RT_CPU1_P1_PERST_N
  F34  SMB_ADDR1  IN  = RT_CPU1_P1_ADDR1
  FA15  GND117  POWER  = GND
  FA32  GND118  POWER  = GND
  FB2  GND119  POWER  = GND
  FB34  GND120  POWER  = GND
  FC3  GND125  POWER  = GND
  FC6  GND126  POWER  = GND
  FC9  GND127  POWER  = GND
  FC19  GND121  POWER  = GND
  FC23  GND122  POWER  = GND
  FC25  GND123  POWER  = GND
  FC28  GND124  POWER  = GND
  FD1  GND128  POWER  = GND
  FD35  GND129  POWER  = GND
  FE2  NCF_GND7  POWER  = NCF_CPU1_P1_GND
  FE34  NCF_GND8  POWER  = NCF_CPU1_P1_GND
  FF5  EE_CLK  BI  = SMB_RT_CPU1_P1_ROM_MUX_1D_R_SCL
  FF8  JTAG_TEST_MODE  IN  = JTAG_TEST_MODE_RT_CPU1_P1
  FF11  RESET_N  IN  = RST_RT_CPU1_P1_RESET_N
  FF14  GND130  POWER  = GND
  FF18  REFCLKN  IN  = CLK_100M_RETIMER_CPU1_P1_DN
  FF21  GND131  POWER  = GND
  FF24  TEST0  BI  = TEST0_RT_CPU1_P1
  FF27  TEST1  BI  = TEST1_RT_CPU1_P1
  FF30  TEST2  BI  = TEST2_RT_CPU1_P1
  FF33  SCAN_MODE  IN  = RT_CPU1_P1_SCAN_MODE
  FG1  NCF_GND9  POWER  = NCF_CPU1_P1_GND
  FG35  NCF_GND10  POWER  = NCF_CPU1_P1_GND
  FH2  NCF_GND11  POWER  = NCF_CPU1_P1_GND
  FH34  NCF_GND12  POWER  = NCF_CPU1_P1_GND
  FJ3  EE_DAT  BI  = SMB_RT_CPU1_P1_ROM_MUX_1D_R_SDA
  FJ6  GPIO0  BI  = NC
  FJ9  MODE  IN  = MODE_RT_CPU1_P1
  FJ12  GND132  POWER  = GND
  FJ16  REFCLKP  IN  = CLK_100M_RETIMER_CPU1_P1_DP
  FJ19  GND133  POWER  = GND
  FJ23  GPIO1  BI  = NC
  FJ25  GPIO2  BI  = GPIO2_RT_CPU1_P1
  FJ28  GPIO3  BI  = GPIO3_RT_CPU1_P1
  FJ31  INT_N  OUT  = NC
  G1  VQPS  IN  = RT_CPU1_P1_VQPS
  G35  CLKREQ_N  IN  = CLKREQ_RT_CPU1_P1_N
  H12  GND134  POWER  = GND
  H16  GND135  POWER  = GND
  H19  GND136  POWER  = GND
  H31  GND137  POWER  = GND
  J4  GND139  POWER  = GND
  J22  GND138  POWER  = GND
  K2  GND140  POWER  = GND
  K34  GND141  POWER  = GND
  L1  GND142  POWER  = GND
  L35  GND143  POWER  = GND
  M7  B_PETP0  OUT  = P5E_CPU1_P1_TX_BUF_DP<15>
  M26  A_PETP0  OUT  = P5E_CPU1_P1_RX_DP<15>
  N2  A_PERN0  IN  = P5E_CPU1_P1_RX_BUF_DN<15>
  N34  B_PERP0  IN  = P5E_CPU1_P1_TX_C_DN<15>
  P10  B_PETN0  OUT  = P5E_CPU1_P1_TX_BUF_DN<15>
  P29  A_PETN0  OUT  = P5E_CPU1_P1_RX_DN<15>
  R1  A_PERP0  IN  = P5E_CPU1_P1_RX_BUF_DP<15>
  R35  B_PERN0  IN  = P5E_CPU1_P1_TX_C_DP<15>
  T4  GND147  POWER  = GND
  T13  GND144  POWER  = GND
  T17  PWR_2A_19  POWER  = P0V9_CPU1_RT1_2A
  T20  PWR_2A_20  POWER  = P0V9_CPU1_RT1_2A
  T22  GND145  POWER  = GND
  T32  GND146  POWER  = GND
  U2  GND148  POWER  = GND
  U34  GND149  POWER  = GND
  V1  GND150  POWER  = GND
  V35  GND151  POWER  = GND
  W7  B_PETP1  OUT  = P5E_CPU1_P1_TX_BUF_DP<14>
  W26  A_PETP1  OUT  = P5E_CPU1_P1_RX_DP<14>
  Y2  A_PERN1  IN  = P5E_CPU1_P1_RX_BUF_DN<14>
  Y34  B_PERP1  IN  = P5E_CPU1_P1_TX_C_DP<14>
